# T6G (Grand Teton) — schematic netlist excerpt (pin names and nets, part order shuffled) for the footprints in the layout excerpt that follows; sources: Cadence DE-HDL packaged netlist, KiCad conversion of 04192023_DAF0TMB3IC0_F0TG_MB_C_brd_V02_OCP.brd

PD102  SCHOTTKY_AC  B340A-13-F IC  pkg D2010XF  page 134 : A = GND ; C = P12V_OCP_SFF
R3280  Q_RES  1K 1% EMPTY  pkg 0402LF  page 111 : A = P3V3_AUX ; B = FM_P2E_EQB1

(kicad_pcb
	(version 20260206)
	(generator "pcbnew")
	(generator_version "10.0")
	(general
		(thickness 1.6)
		(legacy_teardrops no)
	)
	(paper "A4")
	(title_block
		(title "04192023_DAF0TMB3IC0_F0TG_MB_C_brd_V02_OCP.brd")
		(comment 1 "Grand Teton / footprints 279-280 of 8354")
	)
	(layers
		(0 "F.Cu" signal "TOP")
		(4 "In1.Cu" signal "GND")
		(6 "In2.Cu" signal "IN1")
		(8 "In3.Cu" signal "GND1")
		(10 "In4.Cu" signal "IN2")
		(12 "In5.Cu" signal "GND2")
		(14 "In6.Cu" signal "IN3")
		(16 "In7.Cu" signal "GND3")
		(18 "In8.Cu" signal "VCC")
		(20 "In9.Cu" signal "VCC1")
		(22 "In10.Cu" signal "GND4")
		(24 "In11.Cu" signal "IN4")
		(26 "In12.Cu" signal "GND5")
		(28 "In13.Cu" signal "IN5")
		(30 "In14.Cu" signal "GND6")
		(32 "In15.Cu" signal "IN6")
		(34 "In16.Cu" signal "GND7")
		(2 "B.Cu" signal "BOTTOM")
		(9 "F.Adhes" user "F.Adhesive")
		(11 "B.Adhes" user "B.Adhesive")
		(13 "F.Paste" user "Package Geometry/Pastemask Top")
		(15 "B.Paste" user "Package Geometry/Pastemask Bottom")
		(5 "F.SilkS" user "Ref Des/Silkscreen Top")
		(7 "B.SilkS" user "Ref Des/Silkscreen Bottom")
		(1 "F.Mask" user "Board Geometry/Soldermask Top")
		(3 "B.Mask" user "Board Geometry/Soldermask Bottom")
		(17 "Dwgs.User" user "User.Drawings")
		(19 "Cmts.User" user "User.Comments")
		(21 "Eco1.User" user "User.Eco1")
		(23 "Eco2.User" user "User.Eco2")
		(25 "Edge.Cuts" user "Board Geometry/Outline")
		(27 "Margin" user)
		(31 "F.CrtYd" user "Package Geometry/Place Bound Top")
		(29 "B.CrtYd" user "Package Geometry/Place Bound Bottom")
		(35 "F.Fab" user "Ref Des/Assembly Top")
		(33 "B.Fab" user "Ref Des/Assembly Bottom")
	)
	(footprint ""
		(layer "F.Cu")
		(at 455.228452 -15.503398 180)
		(property "Reference" "PD102"
			(at -3.501136 -2.022348 0)
			(unlocked yes)
			(layer "F.SilkS")
			(effects
				(font
					(size 0.7874 0.5842)
					(thickness 0.1524)
				)
				(justify left)
			)
		)
		(property "Value" ""
			(at 0 0 180)
			(layer "F.Fab")
			(effects
				(font
					(size 1.27 1.27)
				)
			)
		)
		(duplicate_pad_numbers_are_jumpers no)
		(fp_line
			(start 4.107942 1.459992)
			(end -3.400044 1.459992)
			(stroke
				(width 0.1524)
				(type default)
			)
			(layer "F.SilkS")
		)
		(fp_line
			(start 4.107942 -1.459992)
			(end 4.107942 1.459992)
			(stroke
				(width 0.1524)
				(type default)
			)
			(layer "F.SilkS")
		)
		(fp_line
			(start -3.400044 1.459992)
			(end -3.400044 -1.459992)
			(stroke
				(width 0.1524)
				(type default)
			)
			(layer "F.SilkS")
		)
		(fp_line
			(start -3.400044 -1.459992)
			(end 4.107942 -1.459992)
			(stroke
				(width 0.1524)
				(type default)
			)
			(layer "F.SilkS")
		)
		(fp_rect
			(start 4.107942 -1.459992)
			(end 3.308096 1.459992)
			(stroke
				(width 0)
				(type default)
			)
			(fill yes)
			(layer "F.SilkS")
		)
		(fp_line
			(start 2.29997 1.459992)
			(end -2.29997 1.459992)
			(stroke
				(width 0.1)
				(type default)
			)
			(layer "F.Fab")
		)
		(fp_line
			(start 2.29997 -1.459992)
			(end 2.29997 1.459992)
			(stroke
				(width 0.1)
				(type default)
			)
			(layer "F.Fab")
		)
		(fp_line
			(start -2.29997 1.459992)
			(end -2.29997 -1.459992)
			(stroke
				(width 0.1)
				(type default)
			)
			(layer "F.Fab")
		)
		(fp_line
			(start -2.29997 -1.459992)
			(end 2.29997 -1.459992)
			(stroke
				(width 0.1)
				(type default)
			)
			(layer "F.Fab")
		)
		(fp_text user "-"
			(at 5.4102 0.29845 0)
			(unlocked yes)
			(layer "F.SilkS")
			(effects
				(font
					(size 1.905 1.4224)
					(thickness 0.1524)
				)
				(justify left)
			)
		)
		(fp_text user "+"
			(at -5.083302 0.161036 180)
			(unlocked yes)
			(layer "F.SilkS")
			(effects
				(font
					(size 1.905 1.4224)
					(thickness 0.1524)
				)
				(justify left)
			)
		)
		(fp_text user "-"
			(at 5.4102 0.29845 0)
			(unlocked yes)
			(layer "F.Fab")
			(effects
				(font
					(size 1.905 1.4224)
					(thickness 0.1524)
				)
				(justify left)
			)
		)
		(fp_text user "+"
			(at -4.7752 -0.12065 180)
			(unlocked yes)
			(layer "F.Fab")
			(effects
				(font
					(size 1.905 1.4224)
					(thickness 0.1524)
				)
				(justify left)
			)
		)
		(pad "A" smd rect
			(at -1.999996 0 270)
			(size 1.7018 2.5146)
			(layers "F.Cu" "F.Mask" "F.Paste")
			(net "GND")
		)
		(pad "C" smd rect
			(at 1.999996 0 270)
			(size 1.7018 2.5146)
			(layers "F.Cu" "F.Mask" "F.Paste")
			(net "P12V_OCP_SFF")
		)
	)
	(footprint ""
		(layer "F.Cu")
		(at 31.331662 -429.759364 -90)
		(property "Reference" "R3280"
			(at 0 0 270)
			(layer "F.SilkS")
			(hide yes)
			(effects
				(font
					(size 1.27 1.27)
				)
			)
		)
		(property "Value" ""
			(at 0 0 270)
			(layer "F.Fab")
			(effects
				(font
					(size 1.27 1.27)
				)
			)
		)
		(duplicate_pad_numbers_are_jumpers no)
		(fp_line
			(start -0.7874 0.4064)
			(end -0.7874 -0.4064)
			(stroke
				(width 0.1524)
				(type default)
			)
			(layer "F.SilkS")
		)
		(fp_line
			(start 0.7874 0.4064)
			(end -0.7874 0.4064)
			(stroke
				(width 0.1524)
				(type default)
			)
			(layer "F.SilkS")
		)
		(fp_line
			(start -0.7874 -0.4064)
			(end 0.7874 -0.4064)
			(stroke
				(width 0.1524)
				(type default)
			)
			(layer "F.SilkS")
		)
		(fp_line
			(start 0.7874 -0.4064)
			(end 0.7874 0.4064)
			(stroke
				(width 0.1524)
				(type default)
			)
			(layer "F.SilkS")
		)
		(fp_line
			(start -0.67945 0.3048)
			(end -0.67945 -0.305054)
			(stroke
				(width 0.1)
				(type default)
			)
			(layer "F.Fab")
		)
		(fp_line
			(start -0.12065 0.3048)
			(end -0.67945 0.3048)
			(stroke
				(width 0.1)
				(type default)
			)
			(layer "F.Fab")
		)
		(fp_line
			(start 0.120396 0.3048)
			(end 0.120396 0.2794)
			(stroke
				(width 0.1)
				(type default)
			)
			(layer "F.Fab")
		)
		(fp_line
			(start 0.67945 0.3048)
			(end 0.120396 0.3048)
			(stroke
				(width 0.1)
				(type default)
			)
			(layer "F.Fab")
		)
		(fp_line
			(start -0.12065 0.2794)
			(end -0.12065 0.3048)
			(stroke
				(width 0.1)
				(type default)
			)
			(layer "F.Fab")
		)
		(fp_line
			(start 0.120396 0.2794)
			(end -0.12065 0.2794)
			(stroke
				(width 0.1)
				(type default)
			)
			(layer "F.Fab")
		)
		(fp_line
			(start -0.12065 -0.2794)
			(end 0.12065 -0.2794)
			(stroke
				(width 0.1)
				(type default)
			)
			(layer "F.Fab")
		)
		(fp_line
			(start 0.12065 -0.2794)
			(end 0.12065 -0.3048)
			(stroke
				(width 0.1)
				(type default)
			)
			(layer "F.Fab")
		)
		(fp_line
			(start 0.12065 -0.3048)
			(end 0.67945 -0.3048)
			(stroke
				(width 0.1)
				(type default)
			)
			(layer "F.Fab")
		)
		(fp_line
			(start 0.67945 -0.3048)
			(end 0.67945 0.3048)
			(stroke
				(width 0.1)
				(type default)
			)
			(layer "F.Fab")
		)
		(fp_line
			(start -0.67945 -0.305054)
			(end -0.12065 -0.305054)
			(stroke
				(width 0.1)
				(type default)
			)
			(layer "F.Fab")
		)
		(fp_line
			(start -0.12065 -0.305054)
			(end -0.12065 -0.2794)
			(stroke
				(width 0.1)
				(type default)
			)
			(layer "F.Fab")
		)
		(pad "1" smd circle
			(at -0.40005 0 270)
			(size 0 0)
			(layers "F.Cu" "F.Mask" "F.Paste")
			(net "P3V3_AUX")
		)
		(pad "2" smd circle
			(at 0.40005 0 270)
			(size 0 0)
			(layers "F.Cu" "F.Mask" "F.Paste")
			(net "FM_P2E_EQB1")
		)
	)
)
